(kicad_pcb
	(version 20221018)
	(generator pcbnew)
	(general
    (thickness 1.7403)
  )
	(paper "A4")
	(title_block
    (title "Data Center RDIMM DDR4 Tester")
    (date "2024-09-30")
    (rev "1.2.4")
		(comment 9 "footprints 170-179 of 690")
	)
	(layers
    (0 "F.Cu" signal)
    (1 "In1.Cu" power)
    (2 "In2.Cu" signal)
    (3 "In3.Cu" power)
    (4 "In4.Cu" power)
    (5 "In5.Cu" signal)
    (6 "In6.Cu" power)
    (7 "In7.Cu" signal)
    (8 "In8.Cu" power)
    (9 "In9.Cu" signal)
    (10 "In10.Cu" power)
    (31 "B.Cu" signal)
    (32 "B.Adhes" user "B.Adhesive")
    (33 "F.Adhes" user "F.Adhesive")
    (34 "B.Paste" user)
    (35 "F.Paste" user)
    (36 "B.SilkS" user "B.Silkscreen")
    (37 "F.SilkS" user "F.Silkscreen")
    (38 "B.Mask" user)
    (39 "F.Mask" user)
    (40 "Dwgs.User" user "User.Drawings")
    (41 "Cmts.User" user "User.Comments")
    (42 "Eco1.User" user "User.Eco1")
    (43 "Eco2.User" user "User.Eco2")
    (44 "Edge.Cuts" user)
    (45 "Margin" user)
    (46 "B.CrtYd" user "B.Courtyard")
    (47 "F.CrtYd" user "F.Courtyard")
    (48 "B.Fab" user)
    (49 "F.Fab" user)
  )
	(footprint "data-center-rdimm-ddr4-tester-footprints:Testpoint_smd_1mm" (layer "F.Cu")
    (at 143.536328 89.810008 90)
    (property "Author" "Antmicro")
    (property "License" "Apache-2.0")
    (property "MPN" "")
    (property "Manufacturer" "")
    (property "Sheetfile" "supply.kicad_sch")
    (property "Sheetname" "Supply")
    (property "ki_description" "Test Point 1mm")
    (attr exclude_from_pos_files)
    (fp_text reference "1V0" (at -0.339992 0.413672 180) (layer "F.SilkS")
        (effects (font (size 0.7 0.7) (thickness 0.15)) (justify left bottom))
    )
    (fp_text value "TP_1mm_SMD" (at 0 1.4 90) (layer "F.Fab") hide
        (effects (font (size 0.7 0.7) (thickness 0.15)) (justify left bottom))
    )
    (fp_text user "License: Apache-2.0" (at -0.5 5.2 90) (layer "F.Fab") hide
        (effects (font (size 0.7 0.7) (thickness 0.15)) (justify left bottom))
    )
    (fp_text user "${REFERENCE}" (at -0.5 2.8 90) (layer "F.Fab") hide
        (effects (font (size 0.7 0.7) (thickness 0.15)) (justify left bottom))
    )
    (fp_text user "Author: Antmicro" (at -0.5 4 90) (layer "F.Fab") hide
        (effects (font (size 0.7 0.7) (thickness 0.15)) (justify left bottom))
    )
    (pad "1" smd circle (at 0 0 90) (size 1 1) (layers "F.Cu" "F.Mask")
      (net 300 "VCC1V0") (pinfunction "1") (pintype "passive"))
  )
	(footprint "data-center-rdimm-ddr4-tester-footprints:C_0402_1005Metric" (layer "F.Cu")
    (at 175.94 107.11 -90)
    (descr "Capacitor SMD 0402")
    (tags "capacitor SMD 0402")
    (property "Author" "Antmicro")
    (property "Dielectric" "X5R")
    (property "License" "Apache-2.0")
    (property "MPN" "GRM155R61H104KE14D")
    (property "Manufacturer" "Murata")
    (property "Sheetfile" "fpga-banks-16-34.kicad_sch")
    (property "Sheetname" "FPGA banks 16-34")
    (property "Val" "100n")
    (property "Voltage" "50V")
    (property "ki_description" " ")
    (attr smd)
    (fp_text reference "C145" (at 1.34 0.6 -90) (layer "F.SilkS")
        (effects (font (size 0.7 0.7) (thickness 0.15)) (justify left bottom))
    )
    (fp_text value "C_100n_0402" (at 0 1.4 -90) (layer "F.Fab") hide
        (effects (font (size 0.7 0.7) (thickness 0.15)) (justify left bottom))
    )
    (fp_text user "License: Apache-2.0" (at -0.932 5.17 -90) (layer "F.Fab") hide
        (effects (font (size 0.7 0.7) (thickness 0.15)) (justify left bottom))
    )
    (fp_text user "${REFERENCE}" (at -0.932 3.168 -90) (layer "F.Fab") hide
        (effects (font (size 0.7 0.7) (thickness 0.15)) (justify left bottom))
    )
    (fp_text user "Author: Antmicro" (at -0.932 4.17 -90) (layer "F.Fab") hide
        (effects (font (size 0.7 0.7) (thickness 0.15)) (justify left bottom))
    )
    (fp_rect (start -0.94 -0.47) (end 0.94 0.47)
      (stroke (width 0.05) (type solid)) (fill none) (layer "F.CrtYd"))
    (fp_rect (start -0.499 -0.249) (end 0.499 0.249)
      (stroke (width 0.15) (type solid)) (fill none) (layer "F.Fab"))
    (pad "1" smd roundrect (at -0.484 0 270) (size 0.59 0.64) (layers "F.Cu" "F.Paste" "F.Mask") (roundrect_rratio 0.25)
      (net 143 "3V3_SYS") (pintype "passive"))
    (pad "2" smd roundrect (at 0.484 0 270) (size 0.59 0.64) (layers "F.Cu" "F.Paste" "F.Mask") (roundrect_rratio 0.25)
      (net 9 "GND") (pintype "passive"))
  )
	(footprint "data-center-rdimm-ddr4-tester-footprints:Oscillator_SMD_Abracon_ASFLMB_5x3.2x0.85mm" (layer "F.Cu")
    (at 179.136328 107.75 90)
    (property "Author" "Antmicro")
    (property "License" "Apache-2.0")
    (property "MPN" "ASFLMB-100.000MHZ-XY-T")
    (property "Manufacturer" "Abracon")
    (property "Sheetfile" "fpga-banks-16-34.kicad_sch")
    (property "Sheetname" "FPGA banks 16-34")
    (property "ki_description" "MEMS OSC XO 100.0000MHZ LVCMOS")
    (property "ki_keywords" "MEMS OSC XO 100.0000MHZ LVCMOS")
    (attr smd)
    (fp_text reference "U1" (at 2.04 -2.756328 180) (layer "F.SilkS")
        (effects (font (size 0.7 0.7) (thickness 0.15)) (justify left bottom))
    )
    (fp_text value "Oscillator_SMD_100MHz_ASFLMB" (at 0 3.8 90) (layer "F.Fab") hide
        (effects (font (size 0.7 0.7) (thickness 0.15)) (justify left bottom))
    )
    (fp_text user "${REFERENCE}" (at -2.8 5.06 90) (layer "F.Fab") hide
        (effects (font (size 0.7 0.7) (thickness 0.15)) (justify left bottom))
    )
    (fp_text user "Author: Antmicro" (at -2.8 6.259 90) (layer "F.Fab") hide
        (effects (font (size 0.7 0.7) (thickness 0.15)) (justify left bottom))
    )
    (fp_text user "License: Apache-2.0" (at -2.8 7.459 90) (layer "F.Fab") hide
        (effects (font (size 0.7 0.7) (thickness 0.15)) (justify left bottom))
    )
    (fp_line (start -1.6 -2.5) (end -1.6 -1.9)
      (stroke (width 0.15) (type solid)) (layer "F.SilkS"))
    (fp_line (start -1.6 -0.4) (end -1.6 0.6)
      (stroke (width 0.15) (type solid)) (layer "F.SilkS"))
    (fp_line (start -1.6 2.1) (end -1.6 2.7)
      (stroke (width 0.15) (type solid)) (layer "F.SilkS"))
    (fp_line (start -1.6 2.7) (end 1.8 2.7)
      (stroke (width 0.15) (type solid)) (layer "F.SilkS"))
    (fp_line (start 1.8 -2.5) (end -1.6 -2.5)
      (stroke (width 0.15) (type solid)) (layer "F.SilkS"))
    (fp_line (start 1.8 -1.9) (end 1.8 -2.5)
      (stroke (width 0.15) (type solid)) (layer "F.SilkS"))
    (fp_line (start 1.8 0.6) (end 1.8 -0.4)
      (stroke (width 0.15) (type solid)) (layer "F.SilkS"))
    (fp_line (start 1.8 2.7) (end 1.8 2.1)
      (stroke (width 0.15) (type solid)) (layer "F.SilkS"))
    (fp_circle (center -1.9 -2.1) (end -1.9 -2.05)
      (stroke (width 0.15) (type solid)) (fill solid) (layer "F.SilkS"))
    (fp_rect (start 2 -2.7) (end -1.8 2.9)
      (stroke (width 0.05) (type solid)) (fill none) (layer "F.CrtYd"))
    (pad "1" smd rect (at -1.049 -1.17 270) (size 1.1 1.2) (layers "F.Cu" "F.Paste" "F.Mask")
      (net 143 "3V3_SYS") (pinfunction "~{STDB}") (pintype "input"))
    (pad "2" smd rect (at -1.049 1.369) (size 1.2 1.1) (layers "F.Cu" "F.Paste" "F.Mask")
      (net 9 "GND") (pinfunction "GND") (pintype "unspecified"))
    (pad "3" smd rect (at 1.252 1.369) (size 1.2 1.1) (layers "F.Cu" "F.Paste" "F.Mask")
      (net 311 "GCLK100") (pinfunction "OUT") (pintype "output"))
    (pad "4" smd rect (at 1.252 -1.17) (size 1.2 1.1) (layers "F.Cu" "F.Paste" "F.Mask")
      (net 143 "3V3_SYS") (pinfunction "V_{DD}") (pintype "power_in"))
  )
	(footprint "data-center-rdimm-ddr4-tester-footprints:Testpoint_smd_1mm" (layer "F.Cu")
    (at 223.5 112.2 180)
    (property "Author" "Antmicro")
    (property "License" "Apache-2.0")
    (property "MPN" "")
    (property "Manufacturer" "")
    (property "Sheetfile" "config-spi.kicad_sch")
    (property "Sheetname" "Config SPI flash")
    (property "ki_description" "Test Point 1mm")
    (attr exclude_from_pos_files)
    (fp_text reference "PUDC_B1" (at 0.64 0.53 180) (layer "F.SilkS")
        (effects (font (size 0.7 0.7) (thickness 0.15)) (justify left bottom))
    )
    (fp_text value "TP_1mm_SMD" (at 0 1.4 180) (layer "F.Fab") hide
        (effects (font (size 0.7 0.7) (thickness 0.15)) (justify left bottom))
    )
    (fp_text user "${REFERENCE}" (at -0.5 2.8 180) (layer "F.Fab") hide
        (effects (font (size 0.7 0.7) (thickness 0.15)) (justify left bottom))
    )
    (fp_text user "Author: Antmicro" (at -0.5 4 180) (layer "F.Fab") hide
        (effects (font (size 0.7 0.7) (thickness 0.15)) (justify left bottom))
    )
    (fp_text user "License: Apache-2.0" (at -0.5 5.2 180) (layer "F.Fab") hide
        (effects (font (size 0.7 0.7) (thickness 0.15)) (justify left bottom))
    )
    (pad "1" smd circle (at 0 0 180) (size 1 1) (layers "F.Cu" "F.Mask")
      (net 79 "PUDC_B") (pinfunction "1") (pintype "passive"))
  )
	(footprint "data-center-rdimm-ddr4-tester-footprints:C_0402_1005Metric" (layer "F.Cu")
    (at 114.41 111.75)
    (descr "Capacitor SMD 0402")
    (tags "capacitor SMD 0402")
    (property "Author" "Antmicro")
    (property "Dielectric" "X5R")
    (property "License" "Apache-2.0")
    (property "MPN" "GRM155R61H104KE14D")
    (property "Manufacturer" "Murata")
    (property "Sheetfile" "supply.kicad_sch")
    (property "Sheetname" "Supply")
    (property "Val" "100n")
    (property "Voltage" "50V")
    (property "ki_description" " ")
    (attr smd)
    (fp_text reference "C178" (at -3.67 0.32) (layer "F.SilkS")
        (effects (font (size 0.7 0.7) (thickness 0.15)) (justify left bottom))
    )
    (fp_text value "C_100n_0402" (at 0 1.4) (layer "F.Fab") hide
        (effects (font (size 0.7 0.7) (thickness 0.15)) (justify left bottom))
    )
    (fp_text user "${REFERENCE}" (at -0.932 3.168) (layer "F.Fab") hide
        (effects (font (size 0.7 0.7) (thickness 0.15)) (justify left bottom))
    )
    (fp_text user "Author: Antmicro" (at -0.932 4.17) (layer "F.Fab") hide
        (effects (font (size 0.7 0.7) (thickness 0.15)) (justify left bottom))
    )
    (fp_text user "License: Apache-2.0" (at -0.932 5.17) (layer "F.Fab") hide
        (effects (font (size 0.7 0.7) (thickness 0.15)) (justify left bottom))
    )
    (fp_rect (start -0.94 -0.47) (end 0.94 0.47)
      (stroke (width 0.05) (type solid)) (fill none) (layer "F.CrtYd"))
    (fp_rect (start -0.499 -0.249) (end 0.499 0.249)
      (stroke (width 0.15) (type solid)) (fill none) (layer "F.Fab"))
    (pad "1" smd roundrect (at -0.484 0) (size 0.59 0.64) (layers "F.Cu" "F.Paste" "F.Mask") (roundrect_rratio 0.25)
      (net 71 "Net-(IC1-BOOT)") (pintype "passive"))
    (pad "2" smd roundrect (at 0.484 0) (size 0.59 0.64) (layers "F.Cu" "F.Paste" "F.Mask") (roundrect_rratio 0.25)
      (net 73 "Net-(IC1-SW)") (pintype "passive"))
  )
	(footprint "data-center-rdimm-ddr4-tester-footprints:R_0402_1005Metric" (layer "F.Cu")
    (at 178.04 63.055 90)
    (descr "Resistor SMD 0402")
    (tags "resistor SMD 0402")
    (property "Author" "Antmicro")
    (property "License" "Apache-2.0")
    (property "MPN" "CR0402-FX-1002GLF")
    (property "Manufacturer" "Bourns")
    (property "Sheetfile" "fpga-banks-16-34.kicad_sch")
    (property "Sheetname" "FPGA banks 16-34")
    (property "Tolerance" "1%")
    (property "Val" "10k")
    (property "ki_description" "10k resistor in 0402 package with 1% tolerance")
    (attr smd)
    (fp_text reference "R163" (at -3.715 0.37 90) (layer "F.SilkS")
        (effects (font (size 0.7 0.7) (thickness 0.15)) (justify left bottom))
    )
    (fp_text value "R_10k_0402" (at 0 1.4 90) (layer "F.Fab") hide
        (effects (font (size 0.7 0.7) (thickness 0.15)) (justify left bottom))
    )
    (fp_text user "License: Apache-2.0" (at -0.95 5.169 90) (layer "F.Fab") hide
        (effects (font (size 0.7 0.7) (thickness 0.15)) (justify left bottom))
    )
    (fp_text user "${REFERENCE}" (at -0.95 3.168 90) (layer "F.Fab") hide
        (effects (font (size 0.7 0.7) (thickness 0.15)) (justify left bottom))
    )
    (fp_text user "Author: Antmicro" (at -0.95 4.169 90) (layer "F.Fab") hide
        (effects (font (size 0.7 0.7) (thickness 0.15)) (justify left bottom))
    )
    (fp_rect (start -0.93 -0.47) (end 0.93 0.47)
      (stroke (width 0.05) (type solid)) (fill none) (layer "F.CrtYd"))
    (fp_rect (start -0.5 -0.25) (end 0.5 0.25)
      (stroke (width 0.15) (type solid)) (fill none) (layer "F.Fab"))
    (pad "1" smd roundrect (at -0.485 0 90) (size 0.59 0.64) (layers "F.Cu" "F.Paste" "F.Mask") (roundrect_rratio 0.25)
      (net 658 "Net-(U15G-IO_L4N_T0_33)") (pintype "passive"))
    (pad "2" smd roundrect (at 0.485 0 90) (size 0.59 0.64) (layers "F.Cu" "F.Paste" "F.Mask") (roundrect_rratio 0.25)
      (net 187 "~{EVENT}") (pintype "passive"))
  )
	(footprint "data-center-rdimm-ddr4-tester-footprints:R_0402_1005Metric" (layer "F.Cu")
    (at 117.336328 64.160008 180)
    (descr "Resistor SMD 0402")
    (tags "resistor SMD 0402")
    (property "Author" "Antmicro")
    (property "Current" "1A")
    (property "DNP" "DNP")
    (property "License" "Apache-2.0")
    (property "MPN" "ERJ2GE0R00X")
    (property "Manufacturer" "Panasonic")
    (property "Sheetfile" "fpga-banks-16-34.kicad_sch")
    (property "Sheetname" "FPGA banks 16-34")
    (property "Tolerance" "")
    (property "Val" "0R")
    (property "dnp" "")
    (property "exclude_from_bom" "")
    (property "ki_description" "0R resistor in 0402 package with unspecified tolerance")
    (attr exclude_from_pos_files exclude_from_bom)
    (fp_text reference "R166" (at -0.813672 -0.349992 180) (layer "F.SilkS")
        (effects (font (size 0.7 0.7) (thickness 0.15)) (justify left bottom))
    )
    (fp_text value "R_0R_0402" (at 0 1.4 180) (layer "F.Fab") hide
        (effects (font (size 0.7 0.7) (thickness 0.15)) (justify left bottom))
    )
    (fp_text user "Author: Antmicro" (at -0.95 4.169 180) (layer "F.Fab") hide
        (effects (font (size 0.7 0.7) (thickness 0.15)) (justify left bottom))
    )
    (fp_text user "${REFERENCE}" (at -0.95 3.168 180) (layer "F.Fab") hide
        (effects (font (size 0.7 0.7) (thickness 0.15)) (justify left bottom))
    )
    (fp_text user "License: Apache-2.0" (at -0.95 5.169 180) (layer "F.Fab") hide
        (effects (font (size 0.7 0.7) (thickness 0.15)) (justify left bottom))
    )
    (fp_rect (start -0.93 -0.47) (end 0.93 0.47)
      (stroke (width 0.05) (type solid)) (fill none) (layer "F.CrtYd"))
    (fp_rect (start -0.5 -0.25) (end 0.5 0.25)
      (stroke (width 0.15) (type solid)) (fill none) (layer "F.Fab"))
    (pad "1" smd roundrect (at -0.485 0 180) (size 0.59 0.64) (layers "F.Cu" "F.Paste" "F.Mask") (roundrect_rratio 0.25)
      (net 185 "VDDSPD") (pintype "passive"))
    (pad "2" smd roundrect (at 0.485 0 180) (size 0.59 0.64) (layers "F.Cu" "F.Paste" "F.Mask") (roundrect_rratio 0.25)
      (net 214 "SA1") (pintype "passive"))
  )
	(footprint "data-center-rdimm-ddr4-tester-footprints:R_0402_1005Metric" (layer "F.Cu")
    (at 117.336328 65.160008 180)
    (descr "Resistor SMD 0402")
    (tags "resistor SMD 0402")
    (property "Author" "Antmicro")
    (property "Current" "1A")
    (property "DNP" "DNP")
    (property "License" "Apache-2.0")
    (property "MPN" "ERJ2GE0R00X")
    (property "Manufacturer" "Panasonic")
    (property "Sheetfile" "fpga-banks-16-34.kicad_sch")
    (property "Sheetname" "FPGA banks 16-34")
    (property "Tolerance" "")
    (property "Val" "0R")
    (property "dnp" "")
    (property "exclude_from_bom" "")
    (property "ki_description" "0R resistor in 0402 package with unspecified tolerance")
    (attr exclude_from_pos_files exclude_from_bom)
    (fp_text reference "R168" (at -0.813672 -0.349992 180) (layer "F.SilkS")
        (effects (font (size 0.7 0.7) (thickness 0.15)) (justify left bottom))
    )
    (fp_text value "R_0R_0402" (at 0 1.4 180) (layer "F.Fab") hide
        (effects (font (size 0.7 0.7) (thickness 0.15)) (justify left bottom))
    )
    (fp_text user "Author: Antmicro" (at -0.95 4.169 180) (layer "F.Fab") hide
        (effects (font (size 0.7 0.7) (thickness 0.15)) (justify left bottom))
    )
    (fp_text user "License: Apache-2.0" (at -0.95 5.169 180) (layer "F.Fab") hide
        (effects (font (size 0.7 0.7) (thickness 0.15)) (justify left bottom))
    )
    (fp_text user "${REFERENCE}" (at -0.95 3.168 180) (layer "F.Fab") hide
        (effects (font (size 0.7 0.7) (thickness 0.15)) (justify left bottom))
    )
    (fp_rect (start -0.93 -0.47) (end 0.93 0.47)
      (stroke (width 0.05) (type solid)) (fill none) (layer "F.CrtYd"))
    (fp_rect (start -0.5 -0.25) (end 0.5 0.25)
      (stroke (width 0.15) (type solid)) (fill none) (layer "F.Fab"))
    (pad "1" smd roundrect (at -0.485 0 180) (size 0.59 0.64) (layers "F.Cu" "F.Paste" "F.Mask") (roundrect_rratio 0.25)
      (net 185 "VDDSPD") (pintype "passive"))
    (pad "2" smd roundrect (at 0.485 0 180) (size 0.59 0.64) (layers "F.Cu" "F.Paste" "F.Mask") (roundrect_rratio 0.25)
      (net 218 "SA0") (pintype "passive"))
  )
	(footprint "data-center-rdimm-ddr4-tester-footprints:R_0402_1005Metric" (layer "F.Cu")
    (at 122.487128 74.106008 180)
    (descr "Resistor SMD 0402")
    (tags "resistor SMD 0402")
    (property "Author" "Antmicro")
    (property "License" "Apache-2.0")
    (property "MPN" "CR0402-FX-4701GLF")
    (property "Manufacturer" "Bourns")
    (property "Sheetfile" "fpga-banks-16-34.kicad_sch")
    (property "Sheetname" "FPGA banks 16-34")
    (property "Tolerance" "1%")
    (property "Val" "4k7")
    (property "ki_description" "4k7 resistor in 0402 package with 1% tolerance")
    (attr smd)
    (fp_text reference "R171" (at -0.802872 -0.373992 180) (layer "F.SilkS")
        (effects (font (size 0.7 0.7) (thickness 0.15)) (justify left bottom))
    )
    (fp_text value "R_4k7_0402" (at 0 1.4 180) (layer "F.Fab") hide
        (effects (font (size 0.7 0.7) (thickness 0.15)) (justify left bottom))
    )
    (fp_text user "License: Apache-2.0" (at -0.95 5.169 180) (layer "F.Fab") hide
        (effects (font (size 0.7 0.7) (thickness 0.15)) (justify left bottom))
    )
    (fp_text user "Author: Antmicro" (at -0.95 4.169 180) (layer "F.Fab") hide
        (effects (font (size 0.7 0.7) (thickness 0.15)) (justify left bottom))
    )
    (fp_text user "${REFERENCE}" (at -0.95 3.168 180) (layer "F.Fab") hide
        (effects (font (size 0.7 0.7) (thickness 0.15)) (justify left bottom))
    )
    (fp_rect (start -0.93 -0.47) (end 0.93 0.47)
      (stroke (width 0.05) (type solid)) (fill none) (layer "F.CrtYd"))
    (fp_rect (start -0.5 -0.25) (end 0.5 0.25)
      (stroke (width 0.15) (type solid)) (fill none) (layer "F.Fab"))
    (pad "1" smd roundrect (at -0.485 0 180) (size 0.59 0.64) (layers "F.Cu" "F.Paste" "F.Mask") (roundrect_rratio 0.25)
      (net 143 "3V3_SYS") (pintype "passive"))
    (pad "2" smd roundrect (at 0.485 0 180) (size 0.59 0.64) (layers "F.Cu" "F.Paste" "F.Mask") (roundrect_rratio 0.25)
      (net 358 "SCL_3V3") (pintype "passive"))
  )
	(footprint "data-center-rdimm-ddr4-tester-footprints:R_0402_1005Metric" (layer "F.Cu")
    (at 122.486328 66.185008 180)
    (descr "Resistor SMD 0402")
    (tags "resistor SMD 0402")
    (property "Author" "Antmicro")
    (property "License" "Apache-2.0")
    (property "MPN" "CR0402-FX-4701GLF")
    (property "Manufacturer" "Bourns")
    (property "Sheetfile" "fpga-banks-16-34.kicad_sch")
    (property "Sheetname" "FPGA banks 16-34")
    (property "Tolerance" "1%")
    (property "Val" "4k7")
    (property "ki_description" "4k7 resistor in 0402 package with 1% tolerance")
    (attr smd)
    (fp_text reference "R174" (at -1.053672 -0.364992 180) (layer "F.SilkS")
        (effects (font (size 0.7 0.7) (thickness 0.15)) (justify left bottom))
    )
    (fp_text value "R_4k7_0402" (at 0 1.4 180) (layer "F.Fab") hide
        (effects (font (size 0.7 0.7) (thickness 0.15)) (justify left bottom))
    )
    (fp_text user "Author: Antmicro" (at -0.95 4.169 180) (layer "F.Fab") hide
        (effects (font (size 0.7 0.7) (thickness 0.15)) (justify left bottom))
    )
    (fp_text user "License: Apache-2.0" (at -0.95 5.169 180) (layer "F.Fab") hide
        (effects (font (size 0.7 0.7) (thickness 0.15)) (justify left bottom))
    )
    (fp_text user "${REFERENCE}" (at -0.95 3.168 180) (layer "F.Fab") hide
        (effects (font (size 0.7 0.7) (thickness 0.15)) (justify left bottom))
    )
    (fp_rect (start -0.93 -0.47) (end 0.93 0.47)
      (stroke (width 0.05) (type solid)) (fill none) (layer "F.CrtYd"))
    (fp_rect (start -0.5 -0.25) (end 0.5 0.25)
      (stroke (width 0.15) (type solid)) (fill none) (layer "F.Fab"))
    (pad "1" smd roundrect (at -0.485 0 180) (size 0.59 0.64) (layers "F.Cu" "F.Paste" "F.Mask") (roundrect_rratio 0.25)
      (net 185 "VDDSPD") (pintype "passive"))
    (pad "2" smd roundrect (at 0.485 0 180) (size 0.59 0.64) (layers "F.Cu" "F.Paste" "F.Mask") (roundrect_rratio 0.25)
      (net 351 "SCL_2V5") (pintype "passive"))
  )
)
